# TIMECARD (Time Appliance Project (Time Card)) — schematic netlist excerpt (pin names and nets, part order shuffled) for the footprints in the layout excerpt that follows; sources: Cadence DE-HDL packaged netlist, KiCad conversion of R4006-B0001-02_R01.brd

R431  RESISTOR  33OHM 1%  pkg SMC_0402R_H016  page 25 : \1\ = UNNAMED_16_CONNHDR2X6FSSMT_I1_5 ; \2\ = FPGA_IO_3
R315  RESISTOR  0OHM -  pkg SMC_0402R_H016  page 19 : \1\ = ICP10100_I2C_SCL ; \2\ = BF_ICP10100_I2C_SCL

(kicad_pcb
	(version 20260206)
	(generator "pcbnew")
	(generator_version "10.0")
	(general
		(thickness 1.6)
		(legacy_teardrops no)
	)
	(paper "A4")
	(title_block
		(title "timecard-production-celestica-r4006 — R4006-B0001-02_R01.brd")
		(comment 1 "Time Appliance Project (Time Card) / footprints 802-803 of 1113")
	)
	(layers
		(0 "F.Cu" signal "TOP")
		(4 "In1.Cu" signal "L02_GND1")
		(6 "In2.Cu" signal "L03_SIG1")
		(8 "In3.Cu" signal "L04_GND2")
		(10 "In4.Cu" signal "L05_VCC1")
		(12 "In5.Cu" signal "L06_VCC2")
		(14 "In6.Cu" signal "L07_GND3")
		(16 "In7.Cu" signal "L08_SIG2")
		(18 "In8.Cu" signal "L09_GND4")
		(2 "B.Cu" signal "BOTTOM")
		(9 "F.Adhes" user "F.Adhesive")
		(11 "B.Adhes" user "B.Adhesive")
		(13 "F.Paste" user "Package Geometry/Pastemask Top")
		(15 "B.Paste" user "Package Geometry/Pastemask Bottom")
		(5 "F.SilkS" user "Ref Des/Silkscreen Top")
		(7 "B.SilkS" user "Ref Des/Silkscreen Bottom")
		(1 "F.Mask" user "Board Geometry/Soldermask Top")
		(3 "B.Mask" user "Board Geometry/Soldermask Bottom")
		(17 "Dwgs.User" user "User.Drawings")
		(19 "Cmts.User" user "User.Comments")
		(21 "Eco1.User" user "User.Eco1")
		(23 "Eco2.User" user "User.Eco2")
		(25 "Edge.Cuts" user "Board Geometry/Outline")
		(27 "Margin" user)
		(31 "F.CrtYd" user "Package Geometry/Place Bound Top")
		(29 "B.CrtYd" user "Package Geometry/Place Bound Bottom")
		(35 "F.Fab" user "Ref Des/Assembly Top")
		(33 "B.Fab" user "Ref Des/Assembly Bottom")
	)
	(footprint ""
		(layer "B.Cu")
		(at 19.304 -61.5442 90)
		(property "Reference" "R315"
			(at -0.381 -3.84937 270)
			(unlocked yes)
			(layer "B.SilkS")
			(effects
				(font
					(size 0.7874 0.5842)
					(thickness 0.1524)
				)
				(justify mirror)
			)
		)
		(property "Value" "VAL*"
			(at -0.02032 2.13233 90)
			(unlocked yes)
			(layer "B.Fab")
			(hide yes)
			(effects
				(font
					(size 0.7874 0.5842)
					(thickness 0.1524)
				)
				(justify mirror)
			)
		)
		(property "Tolerance" "TOL*"
			(at -0.044704 3.05435 90)
			(unlocked yes)
			(layer "Cmts.User")
			(hide yes)
			(effects
				(font
					(size 0.7874 0.5842)
					(thickness 0.1524)
				)
				(justify mirror)
			)
		)
		(property "User Part Number" "PARTNUM*"
			(at -0.02032 4.024884 90)
			(unlocked yes)
			(layer "Cmts.User")
			(hide yes)
			(effects
				(font
					(size 0.7874 0.5842)
					(thickness 0.1524)
				)
				(justify mirror)
			)
		)
		(property "Device Type" "RESISTOR-G155-100R0-J0,0OHM,-"
			(at -0.008382 1.210564 90)
			(unlocked yes)
			(layer "B.Fab")
			(hide yes)
			(effects
				(font
					(size 0.7874 0.5842)
					(thickness 0.1524)
				)
				(justify mirror)
			)
		)
		(duplicate_pad_numbers_are_jumpers no)
		(fp_line
			(start 1.143 -0.5588)
			(end 1.143 0.5588)
			(stroke
				(width 0.1)
				(type default)
			)
			(layer "B.SilkS")
		)
		(fp_line
			(start -1.143 -0.5588)
			(end 1.143 -0.5588)
			(stroke
				(width 0.1)
				(type default)
			)
			(layer "B.SilkS")
		)
		(fp_line
			(start 1.143 0.5588)
			(end -1.143 0.5588)
			(stroke
				(width 0.1)
				(type default)
			)
			(layer "B.SilkS")
		)
		(fp_line
			(start -1.143 0.5588)
			(end -1.143 -0.5588)
			(stroke
				(width 0.1)
				(type default)
			)
			(layer "B.SilkS")
		)
		(fp_poly
			(pts
				(xy 1.143 0.5588) (xy -1.143 0.5588) (xy -1.143 -0.5588) (xy 1.143 -0.5588)
			)
			(stroke
				(width 0)
				(type default)
			)
			(fill no)
			(layer "B.CrtYd")
		)
		(fp_line
			(start 0.508 -0.3048)
			(end 0.508 0.3048)
			(stroke
				(width 0.1)
				(type default)
			)
			(layer "B.Fab")
		)
		(fp_line
			(start -0.508 -0.3048)
			(end 0.508 -0.3048)
			(stroke
				(width 0.1)
				(type default)
			)
			(layer "B.Fab")
		)
		(fp_line
			(start 0.508 0.3048)
			(end -0.508 0.3048)
			(stroke
				(width 0.1)
				(type default)
			)
			(layer "B.Fab")
		)
		(fp_line
			(start -0.508 0.3048)
			(end -0.508 -0.3048)
			(stroke
				(width 0.1)
				(type default)
			)
			(layer "B.Fab")
		)
		(pad "1" smd rect
			(at 0.5334 0 270)
			(size 0.7112 0.6096)
			(layers "B.Cu" "B.Mask" "B.Paste")
			(net "ICP10100_I2C_SCL")
		)
		(pad "2" smd rect
			(at -0.5334 0 270)
			(size 0.7112 0.6096)
			(layers "B.Cu" "B.Mask" "B.Paste")
			(net "BF_ICP10100_I2C_SCL")
		)
		(zone
			(layer "B.Cu")
			(hatch none 0.5)
			(connect_pads
				(clearance 0)
			)
			(min_thickness 0.25)
			(keepout
				(tracks allowed)
				(vias not_allowed)
				(pads allowed)
				(copperpour not_allowed)
				(footprints allowed)
			)
			(placement
				(enabled no)
				(sheetname "")
			)
			(fill
				(thermal_gap 0.5)
				(thermal_bridge_width 0.5)
				(island_removal_mode 0)
			)
			(polygon
				(pts
					(xy 19.6088 -61.6204) (xy 18.9992 -61.6204) (xy 18.9992 -61.468) (xy 19.6088 -61.468)
				)
			)
		)
		(zone
			(layer "B.Cu")
			(hatch none 0.5)
			(connect_pads
				(clearance 0)
			)
			(min_thickness 0.25)
			(keepout
				(tracks not_allowed)
				(vias allowed)
				(pads allowed)
				(copperpour not_allowed)
				(footprints allowed)
			)
			(placement
				(enabled no)
				(sheetname "")
			)
			(fill
				(thermal_gap 0.5)
				(thermal_bridge_width 0.5)
				(island_removal_mode 0)
			)
			(polygon
				(pts
					(xy 19.6088 -61.6204) (xy 18.9992 -61.6204) (xy 18.9992 -61.468) (xy 19.6088 -61.468)
				)
			)
		)
	)
	(footprint ""
		(layer "B.Cu")
		(at 151.892 -36.576 90)
		(property "Reference" "R431"
			(at -4.99237 0.635 0)
			(unlocked yes)
			(layer "B.SilkS")
			(effects
				(font
					(size 0.7874 0.5842)
					(thickness 0.1524)
				)
				(justify mirror)
			)
		)
		(property "Value" "VAL*"
			(at -0.02032 2.13233 90)
			(unlocked yes)
			(layer "B.Fab")
			(hide yes)
			(effects
				(font
					(size 0.7874 0.5842)
					(thickness 0.1524)
				)
				(justify mirror)
			)
		)
		(property "Tolerance" "TOL*"
			(at -0.044704 3.05435 90)
			(unlocked yes)
			(layer "Cmts.User")
			(hide yes)
			(effects
				(font
					(size 0.7874 0.5842)
					(thickness 0.1524)
				)
				(justify mirror)
			)
		)
		(property "User Part Number" "PARTNUM*"
			(at -0.02032 4.024884 90)
			(unlocked yes)
			(layer "Cmts.User")
			(hide yes)
			(effects
				(font
					(size 0.7874 0.5842)
					(thickness 0.1524)
				)
				(justify mirror)
			)
		)
		(property "Device Type" "RESISTOR-G155-133R0-01,33OHM,1%"
			(at -0.008382 1.210564 90)
			(unlocked yes)
			(layer "B.Fab")
			(hide yes)
			(effects
				(font
					(size 0.7874 0.5842)
					(thickness 0.1524)
				)
				(justify mirror)
			)
		)
		(duplicate_pad_numbers_are_jumpers no)
		(fp_line
			(start 1.143 -0.5588)
			(end 1.143 0.5588)
			(stroke
				(width 0.1)
				(type default)
			)
			(layer "B.SilkS")
		)
		(fp_line
			(start -1.143 -0.5588)
			(end 1.143 -0.5588)
			(stroke
				(width 0.1)
				(type default)
			)
			(layer "B.SilkS")
		)
		(fp_line
			(start 1.143 0.5588)
			(end -1.143 0.5588)
			(stroke
				(width 0.1)
				(type default)
			)
			(layer "B.SilkS")
		)
		(fp_line
			(start -1.143 0.5588)
			(end -1.143 -0.5588)
			(stroke
				(width 0.1)
				(type default)
			)
			(layer "B.SilkS")
		)
		(fp_poly
			(pts
				(xy 1.143 0.5588) (xy -1.143 0.5588) (xy -1.143 -0.5588) (xy 1.143 -0.5588)
			)
			(stroke
				(width 0)
				(type default)
			)
			(fill no)
			(layer "B.CrtYd")
		)
		(fp_line
			(start 0.508 -0.3048)
			(end 0.508 0.3048)
			(stroke
				(width 0.1)
				(type default)
			)
			(layer "B.Fab")
		)
		(fp_line
			(start -0.508 -0.3048)
			(end 0.508 -0.3048)
			(stroke
				(width 0.1)
				(type default)
			)
			(layer "B.Fab")
		)
		(fp_line
			(start 0.508 0.3048)
			(end -0.508 0.3048)
			(stroke
				(width 0.1)
				(type default)
			)
			(layer "B.Fab")
		)
		(fp_line
			(start -0.508 0.3048)
			(end -0.508 -0.3048)
			(stroke
				(width 0.1)
				(type default)
			)
			(layer "B.Fab")
		)
		(pad "1" smd rect
			(at 0.5334 0 270)
			(size 0.7112 0.6096)
			(layers "B.Cu" "B.Mask" "B.Paste")
			(net "UNNAMED_16_CONNHDR2X6FSSMT_I1_5")
		)
		(pad "2" smd rect
			(at -0.5334 0 270)
			(size 0.7112 0.6096)
			(layers "B.Cu" "B.Mask" "B.Paste")
			(net "FPGA_IO_3")
		)
		(zone
			(layer "B.Cu")
			(hatch none 0.5)
			(connect_pads
				(clearance 0)
			)
			(min_thickness 0.25)
			(keepout
				(tracks allowed)
				(vias not_allowed)
				(pads allowed)
				(copperpour not_allowed)
				(footprints allowed)
			)
			(placement
				(enabled no)
				(sheetname "")
			)
			(fill
				(thermal_gap 0.5)
				(thermal_bridge_width 0.5)
				(island_removal_mode 0)
			)
			(polygon
				(pts
					(xy 152.1968 -36.6522) (xy 151.5872 -36.6522) (xy 151.5872 -36.4998) (xy 152.1968 -36.4998)
				)
			)
		)
		(zone
			(layer "B.Cu")
			(hatch none 0.5)
			(connect_pads
				(clearance 0)
			)
			(min_thickness 0.25)
			(keepout
				(tracks not_allowed)
				(vias allowed)
				(pads allowed)
				(copperpour not_allowed)
				(footprints allowed)
			)
			(placement
				(enabled no)
				(sheetname "")
			)
			(fill
				(thermal_gap 0.5)
				(thermal_bridge_width 0.5)
				(island_removal_mode 0)
			)
			(polygon
				(pts
					(xy 152.1968 -36.6522) (xy 151.5872 -36.6522) (xy 151.5872 -36.4998) (xy 152.1968 -36.4998)
				)
			)
		)
	)
)
